# T6G (Grand Teton) — schematic netlist excerpt (pin names and nets, part order shuffled) for the footprints in the layout excerpt that follows; sources: Cadence DE-HDL packaged netlist, KiCad conversion of 04192023_DAF0TMB3IC0_F0TG_MB_C_brd_V02_OCP.brd

TP13  TP  NA  pkg TP  page 54 : TP = VSENSE_VSS_SENSE_C_P1
R2667  Q_RES  2.2K 5% CHIP  pkg 0402LF  page 248 : A = P3V3_AUX ; B = SMB_BMC_SWB_BUF_R_SCL
R946  Q_RES  4.7K 5% CHIP  pkg 0402LF  page 166 : A = P3V3_AUX ; B = BOOT_RDY_LED

(kicad_pcb
	(version 20260206)
	(generator "pcbnew")
	(generator_version "10.0")
	(general
		(thickness 1.6)
		(legacy_teardrops no)
	)
	(paper "A4")
	(title_block
		(title "04192023_DAF0TMB3IC0_F0TG_MB_C_brd_V02_OCP.brd")
		(comment 1 "Grand Teton / footprints 2443-2445 of 8354")
	)
	(layers
		(0 "F.Cu" signal "TOP")
		(4 "In1.Cu" signal "GND")
		(6 "In2.Cu" signal "IN1")
		(8 "In3.Cu" signal "GND1")
		(10 "In4.Cu" signal "IN2")
		(12 "In5.Cu" signal "GND2")
		(14 "In6.Cu" signal "IN3")
		(16 "In7.Cu" signal "GND3")
		(18 "In8.Cu" signal "VCC")
		(20 "In9.Cu" signal "VCC1")
		(22 "In10.Cu" signal "GND4")
		(24 "In11.Cu" signal "IN4")
		(26 "In12.Cu" signal "GND5")
		(28 "In13.Cu" signal "IN5")
		(30 "In14.Cu" signal "GND6")
		(32 "In15.Cu" signal "IN6")
		(34 "In16.Cu" signal "GND7")
		(2 "B.Cu" signal "BOTTOM")
		(9 "F.Adhes" user "F.Adhesive")
		(11 "B.Adhes" user "B.Adhesive")
		(13 "F.Paste" user "Package Geometry/Pastemask Top")
		(15 "B.Paste" user "Package Geometry/Pastemask Bottom")
		(5 "F.SilkS" user "Ref Des/Silkscreen Top")
		(7 "B.SilkS" user "Ref Des/Silkscreen Bottom")
		(1 "F.Mask" user "Board Geometry/Soldermask Top")
		(3 "B.Mask" user "Board Geometry/Soldermask Bottom")
		(17 "Dwgs.User" user "User.Drawings")
		(19 "Cmts.User" user "User.Comments")
		(21 "Eco1.User" user "User.Eco1")
		(23 "Eco2.User" user "User.Eco2")
		(25 "Edge.Cuts" user "Board Geometry/Outline")
		(27 "Margin" user)
		(31 "F.CrtYd" user "Package Geometry/Place Bound Top")
		(29 "B.CrtYd" user "Package Geometry/Place Bound Bottom")
		(35 "F.Fab" user "Ref Des/Assembly Top")
		(33 "B.Fab" user "Ref Des/Assembly Bottom")
	)
	(footprint ""
		(layer "F.Cu")
		(at 342.442546 -23.897336 -90)
		(property "Reference" "R946"
			(at 0 0 270)
			(layer "F.SilkS")
			(hide yes)
			(effects
				(font
					(size 1.27 1.27)
				)
			)
		)
		(property "Value" ""
			(at 0 0 270)
			(layer "F.Fab")
			(effects
				(font
					(size 1.27 1.27)
				)
			)
		)
		(duplicate_pad_numbers_are_jumpers no)
		(fp_line
			(start -0.7874 0.4064)
			(end -0.7874 -0.4064)
			(stroke
				(width 0.1524)
				(type default)
			)
			(layer "F.SilkS")
		)
		(fp_line
			(start 0.7874 0.4064)
			(end -0.7874 0.4064)
			(stroke
				(width 0.1524)
				(type default)
			)
			(layer "F.SilkS")
		)
		(fp_line
			(start -0.7874 -0.4064)
			(end 0.7874 -0.4064)
			(stroke
				(width 0.1524)
				(type default)
			)
			(layer "F.SilkS")
		)
		(fp_line
			(start 0.7874 -0.4064)
			(end 0.7874 0.4064)
			(stroke
				(width 0.1524)
				(type default)
			)
			(layer "F.SilkS")
		)
		(fp_line
			(start -0.67945 0.3048)
			(end -0.67945 -0.305054)
			(stroke
				(width 0.1)
				(type default)
			)
			(layer "F.Fab")
		)
		(fp_line
			(start -0.12065 0.3048)
			(end -0.67945 0.3048)
			(stroke
				(width 0.1)
				(type default)
			)
			(layer "F.Fab")
		)
		(fp_line
			(start 0.120396 0.3048)
			(end 0.120396 0.2794)
			(stroke
				(width 0.1)
				(type default)
			)
			(layer "F.Fab")
		)
		(fp_line
			(start 0.67945 0.3048)
			(end 0.120396 0.3048)
			(stroke
				(width 0.1)
				(type default)
			)
			(layer "F.Fab")
		)
		(fp_line
			(start -0.12065 0.2794)
			(end -0.12065 0.3048)
			(stroke
				(width 0.1)
				(type default)
			)
			(layer "F.Fab")
		)
		(fp_line
			(start 0.120396 0.2794)
			(end -0.12065 0.2794)
			(stroke
				(width 0.1)
				(type default)
			)
			(layer "F.Fab")
		)
		(fp_line
			(start -0.12065 -0.2794)
			(end 0.12065 -0.2794)
			(stroke
				(width 0.1)
				(type default)
			)
			(layer "F.Fab")
		)
		(fp_line
			(start 0.12065 -0.2794)
			(end 0.12065 -0.3048)
			(stroke
				(width 0.1)
				(type default)
			)
			(layer "F.Fab")
		)
		(fp_line
			(start 0.12065 -0.3048)
			(end 0.67945 -0.3048)
			(stroke
				(width 0.1)
				(type default)
			)
			(layer "F.Fab")
		)
		(fp_line
			(start 0.67945 -0.3048)
			(end 0.67945 0.3048)
			(stroke
				(width 0.1)
				(type default)
			)
			(layer "F.Fab")
		)
		(fp_line
			(start -0.67945 -0.305054)
			(end -0.12065 -0.305054)
			(stroke
				(width 0.1)
				(type default)
			)
			(layer "F.Fab")
		)
		(fp_line
			(start -0.12065 -0.305054)
			(end -0.12065 -0.2794)
			(stroke
				(width 0.1)
				(type default)
			)
			(layer "F.Fab")
		)
		(pad "1" smd circle
			(at -0.40005 0 270)
			(size 0 0)
			(layers "F.Cu" "F.Mask" "F.Paste")
			(net "P3V3_AUX")
		)
		(pad "2" smd circle
			(at 0.40005 0 270)
			(size 0 0)
			(layers "F.Cu" "F.Mask" "F.Paste")
			(net "BOOT_RDY_LED")
		)
	)
	(footprint ""
		(layer "F.Cu")
		(at 166.8272 -429.9712 90)
		(property "Reference" "R2667"
			(at 0 0 90)
			(layer "F.SilkS")
			(hide yes)
			(effects
				(font
					(size 1.27 1.27)
				)
			)
		)
		(property "Value" ""
			(at 0 0 90)
			(layer "F.Fab")
			(effects
				(font
					(size 1.27 1.27)
				)
			)
		)
		(duplicate_pad_numbers_are_jumpers no)
		(fp_line
			(start 0.7874 -0.4064)
			(end 0.7874 0.4064)
			(stroke
				(width 0.1524)
				(type default)
			)
			(layer "F.SilkS")
		)
		(fp_line
			(start -0.7874 -0.4064)
			(end 0.7874 -0.4064)
			(stroke
				(width 0.1524)
				(type default)
			)
			(layer "F.SilkS")
		)
		(fp_line
			(start 0.7874 0.4064)
			(end -0.7874 0.4064)
			(stroke
				(width 0.1524)
				(type default)
			)
			(layer "F.SilkS")
		)
		(fp_line
			(start -0.7874 0.4064)
			(end -0.7874 -0.4064)
			(stroke
				(width 0.1524)
				(type default)
			)
			(layer "F.SilkS")
		)
		(fp_line
			(start -0.12065 -0.305054)
			(end -0.12065 -0.2794)
			(stroke
				(width 0.1)
				(type default)
			)
			(layer "F.Fab")
		)
		(fp_line
			(start -0.67945 -0.305054)
			(end -0.12065 -0.305054)
			(stroke
				(width 0.1)
				(type default)
			)
			(layer "F.Fab")
		)
		(fp_line
			(start 0.67945 -0.3048)
			(end 0.67945 0.3048)
			(stroke
				(width 0.1)
				(type default)
			)
			(layer "F.Fab")
		)
		(fp_line
			(start 0.12065 -0.3048)
			(end 0.67945 -0.3048)
			(stroke
				(width 0.1)
				(type default)
			)
			(layer "F.Fab")
		)
		(fp_line
			(start 0.12065 -0.2794)
			(end 0.12065 -0.3048)
			(stroke
				(width 0.1)
				(type default)
			)
			(layer "F.Fab")
		)
		(fp_line
			(start -0.12065 -0.2794)
			(end 0.12065 -0.2794)
			(stroke
				(width 0.1)
				(type default)
			)
			(layer "F.Fab")
		)
		(fp_line
			(start 0.120396 0.2794)
			(end -0.12065 0.2794)
			(stroke
				(width 0.1)
				(type default)
			)
			(layer "F.Fab")
		)
		(fp_line
			(start -0.12065 0.2794)
			(end -0.12065 0.3048)
			(stroke
				(width 0.1)
				(type default)
			)
			(layer "F.Fab")
		)
		(fp_line
			(start 0.67945 0.3048)
			(end 0.120396 0.3048)
			(stroke
				(width 0.1)
				(type default)
			)
			(layer "F.Fab")
		)
		(fp_line
			(start 0.120396 0.3048)
			(end 0.120396 0.2794)
			(stroke
				(width 0.1)
				(type default)
			)
			(layer "F.Fab")
		)
		(fp_line
			(start -0.12065 0.3048)
			(end -0.67945 0.3048)
			(stroke
				(width 0.1)
				(type default)
			)
			(layer "F.Fab")
		)
		(fp_line
			(start -0.67945 0.3048)
			(end -0.67945 -0.305054)
			(stroke
				(width 0.1)
				(type default)
			)
			(layer "F.Fab")
		)
		(pad "1" smd circle
			(at -0.40005 0 90)
			(size 0 0)
			(layers "F.Cu" "F.Mask" "F.Paste")
			(net "P3V3_AUX")
		)
		(pad "2" smd circle
			(at 0.40005 0 90)
			(size 0 0)
			(layers "F.Cu" "F.Mask" "F.Paste")
			(net "SMB_BMC_SWB_BUF_R_SCL")
		)
	)
	(footprint ""
		(layer "F.Cu")
		(at 169.1894 -332.244192 180)
		(property "Reference" "TP13"
			(at 2.356612 5.244846 0)
			(unlocked yes)
			(layer "F.SilkS")
			(effects
				(font
					(size 0.7874 0.5842)
					(thickness 0.1524)
				)
				(justify left)
			)
		)
		(property "Value" ""
			(at 0 0 180)
			(layer "F.Fab")
			(effects
				(font
					(size 1.27 1.27)
				)
			)
		)
		(duplicate_pad_numbers_are_jumpers no)
		(pad "1" smd circle
			(at 0 0 180)
			(size 0.762 0.762)
			(layers "F.Cu" "F.Mask" "F.Paste")
			(net "VSENSE_VSS_SENSE_C_P1")
		)
	)
)
